# S9S_MB_2U (Grand Teton) — schematic netlist excerpt (pin names and nets, part order shuffled) for the footprints in the layout excerpt that follows; sources: Cadence DE-HDL packaged netlist, KiCad conversion of 03242023_DA0F0TMBIJ0_F0T_Motherboard_J_brd_V01_OCP.brd

R2344  Q_RES  4.7K 5% CHIP  pkg 0402LF  page 213 : A = P3V3_AUX ; B = PWRGD_P5V_AUX_R1

(kicad_pcb
	(version 20260206)
	(generator "pcbnew")
	(generator_version "10.0")
	(general
		(thickness 1.6)
		(legacy_teardrops no)
	)
	(paper "A4")
	(title_block
		(title "03242023_DA0F0TMBIJ0_F0T_Motherboard_J_brd_V01_OCP.brd")
		(comment 1 "Grand Teton / footprints 795-795 of 6105")
	)
	(layers
		(0 "F.Cu" signal "TOP")
		(4 "In1.Cu" signal "GND")
		(6 "In2.Cu" signal "IN1")
		(8 "In3.Cu" signal "GND1")
		(10 "In4.Cu" signal "IN2")
		(12 "In5.Cu" signal "GND2")
		(14 "In6.Cu" signal "IN3")
		(16 "In7.Cu" signal "GND3")
		(18 "In8.Cu" signal "VCC")
		(20 "In9.Cu" signal "VCC1")
		(22 "In10.Cu" signal "GND4")
		(24 "In11.Cu" signal "IN4")
		(26 "In12.Cu" signal "GND5")
		(28 "In13.Cu" signal "IN5")
		(30 "In14.Cu" signal "GND6")
		(32 "In15.Cu" signal "IN6")
		(34 "In16.Cu" signal "GND7")
		(2 "B.Cu" signal "BOTTOM")
		(9 "F.Adhes" user "F.Adhesive")
		(11 "B.Adhes" user "B.Adhesive")
		(13 "F.Paste" user "Package Geometry/Pastemask Top")
		(15 "B.Paste" user "Package Geometry/Pastemask Bottom")
		(5 "F.SilkS" user "Ref Des/Silkscreen Top")
		(7 "B.SilkS" user "Ref Des/Silkscreen Bottom")
		(1 "F.Mask" user "Board Geometry/Soldermask Top")
		(3 "B.Mask" user "Board Geometry/Soldermask Bottom")
		(17 "Dwgs.User" user "User.Drawings")
		(19 "Cmts.User" user "User.Comments")
		(21 "Eco1.User" user "User.Eco1")
		(23 "Eco2.User" user "User.Eco2")
		(25 "Edge.Cuts" user "Board Geometry/Outline")
		(27 "Margin" user)
		(31 "F.CrtYd" user "Package Geometry/Place Bound Top")
		(29 "B.CrtYd" user "Package Geometry/Place Bound Bottom")
		(35 "F.Fab" user "Ref Des/Assembly Top")
		(33 "B.Fab" user "Ref Des/Assembly Bottom")
	)
	(footprint ""
		(layer "F.Cu")
		(at 152.70988 -122.519948)
		(property "Reference" "R2344"
			(at 0 0 0)
			(layer "F.SilkS")
			(hide yes)
			(effects
				(font
					(size 1.27 1.27)
				)
			)
		)
		(property "Value" ""
			(at 0 0 0)
			(layer "F.Fab")
			(effects
				(font
					(size 1.27 1.27)
				)
			)
		)
		(duplicate_pad_numbers_are_jumpers no)
		(fp_line
			(start -0.7874 -0.4064)
			(end 0.7874 -0.4064)
			(stroke
				(width 0.1524)
				(type default)
			)
			(layer "F.SilkS")
		)
		(fp_line
			(start -0.7874 0.4064)
			(end -0.7874 -0.4064)
			(stroke
				(width 0.1524)
				(type default)
			)
			(layer "F.SilkS")
		)
		(fp_line
			(start 0.7874 -0.4064)
			(end 0.7874 0.4064)
			(stroke
				(width 0.1524)
				(type default)
			)
			(layer "F.SilkS")
		)
		(fp_line
			(start 0.7874 0.4064)
			(end -0.7874 0.4064)
			(stroke
				(width 0.1524)
				(type default)
			)
			(layer "F.SilkS")
		)
		(fp_line
			(start -0.67945 -0.305054)
			(end -0.12065 -0.305054)
			(stroke
				(width 0.1)
				(type default)
			)
			(layer "F.Fab")
		)
		(fp_line
			(start -0.67945 0.3048)
			(end -0.67945 -0.305054)
			(stroke
				(width 0.1)
				(type default)
			)
			(layer "F.Fab")
		)
		(fp_line
			(start -0.12065 -0.305054)
			(end -0.12065 -0.2794)
			(stroke
				(width 0.1)
				(type default)
			)
			(layer "F.Fab")
		)
		(fp_line
			(start -0.12065 -0.2794)
			(end 0.12065 -0.2794)
			(stroke
				(width 0.1)
				(type default)
			)
			(layer "F.Fab")
		)
		(fp_line
			(start -0.12065 0.2794)
			(end -0.12065 0.3048)
			(stroke
				(width 0.1)
				(type default)
			)
			(layer "F.Fab")
		)
		(fp_line
			(start -0.12065 0.3048)
			(end -0.67945 0.3048)
			(stroke
				(width 0.1)
				(type default)
			)
			(layer "F.Fab")
		)
		(fp_line
			(start 0.120396 0.2794)
			(end -0.12065 0.2794)
			(stroke
				(width 0.1)
				(type default)
			)
			(layer "F.Fab")
		)
		(fp_line
			(start 0.120396 0.3048)
			(end 0.120396 0.2794)
			(stroke
				(width 0.1)
				(type default)
			)
			(layer "F.Fab")
		)
		(fp_line
			(start 0.12065 -0.3048)
			(end 0.67945 -0.3048)
			(stroke
				(width 0.1)
				(type default)
			)
			(layer "F.Fab")
		)
		(fp_line
			(start 0.12065 -0.2794)
			(end 0.12065 -0.3048)
			(stroke
				(width 0.1)
				(type default)
			)
			(layer "F.Fab")
		)
		(fp_line
			(start 0.67945 -0.3048)
			(end 0.67945 0.3048)
			(stroke
				(width 0.1)
				(type default)
			)
			(layer "F.Fab")
		)
		(fp_line
			(start 0.67945 0.3048)
			(end 0.120396 0.3048)
			(stroke
				(width 0.1)
				(type default)
			)
			(layer "F.Fab")
		)
		(pad "1" smd circle
			(at -0.40005 0)
			(size 0 0)
			(layers "F.Cu" "F.Mask" "F.Paste")
			(net "P3V3_AUX")
		)
		(pad "2" smd circle
			(at 0.40005 0)
			(size 0 0)
			(layers "F.Cu" "F.Mask" "F.Paste")
			(net "PWRGD_P5V_AUX_R1")
		)
	)
)
